G04 ================== begin FILE IDENTIFICATION RECORD ==================*
G04 Layout Name:  16368-sb.brd*
G04 Film Name:    L1*
G04 File Format:  Gerber RS274X*
G04 File Origin:  Cadence Allegro 16.5-S056*
G04 Origin Date:  Tue Feb 07 09:07:43 2017*
G04 *
G04 Layer:  VIA CLASS/TOP*
G04 Layer:  PIN/TOP*
G04 Layer:  ETCH/TOP*
G04 Layer:  DRAWING FORMAT/LAYER_PCB_STORY*
G04 Layer:  DRAWING FORMAT/LAYER_L1*
G04 *
G04 Offset:    (0.00 0.00)*
G04 Mirror:    No*
G04 Mode:      Positive*
G04 Rotation:  0*
G04 FullContactRelief:  No*
G04 UndefLineWidth:     6.00*
G04 ================== end FILE IDENTIFICATION RECORD ====================*
%FSLAX35Y35*MOIN*%
%IR0*IPPOS*OFA0.00000B0.00000*MIA0B0*SFA1.00000B1.00000*%
%AMMACRO13*
21,1,.041,.02,0.0,0.0,141.*%
%ADD13MACRO13*%
%ADD11C,.01*%
%ADD17C,.02*%
%ADD10C,.04*%
%ADD15C,.042*%
%ADD12C,.034*%
%ADD26C,.026*%
%AMMACRO33*
4,1,40,.011,-.007,
.011,.007,
.010939,.007695,
.010759,.008368,
.010464,.009,
.010064,.009571,
.009571,.010064,
.009,.010464,
.008368,.010759,
.007695,.010939,
.007,.011,
-.007,.011,
-.007695,.010939,
-.008368,.010759,
-.009,.010464,
-.009571,.010064,
-.010064,.009571,
-.010464,.009,
-.010759,.008368,
-.010939,.007695,
-.011,.007,
-.011,-.007,
-.010939,-.007695,
-.010759,-.008368,
-.010464,-.009,
-.010064,-.009571,
-.009571,-.010064,
-.009,-.010464,
-.008368,-.010759,
-.007695,-.010939,
-.007,-.011,
.007,-.011,
.007695,-.010939,
.008368,-.010759,
.009,-.010464,
.009571,-.010064,
.010064,-.009571,
.010464,-.009,
.010759,-.008368,
.010939,-.007695,
.011,-.007,
0.0*
%
%ADD33MACRO33*%
%AMMACRO21*
4,1,40,.007,.011,
-.007,.011,
-.007695,.010939,
-.008368,.010759,
-.009,.010464,
-.009571,.010064,
-.010064,.009571,
-.010464,.009,
-.010759,.008368,
-.010939,.007695,
-.011,.007,
-.011,-.007,
-.010939,-.007695,
-.010759,-.008368,
-.010464,-.009,
-.010064,-.009571,
-.009571,-.010064,
-.009,-.010464,
-.008368,-.010759,
-.007695,-.010939,
-.007,-.011,
.007,-.011,
.007695,-.010939,
.008368,-.010759,
.009,-.010464,
.009571,-.010064,
.010064,-.009571,
.010464,-.009,
.010759,-.008368,
.010939,-.007695,
.011,-.007,
.011,.007,
.010939,.007695,
.010759,.008368,
.010464,.009,
.010064,.009571,
.009571,.010064,
.009,.010464,
.008368,.010759,
.007695,.010939,
.007,.011,
0.0*
%
%ADD21MACRO21*%
%AMMACRO34*
4,1,40,.011,-.007,
.011,.007,
.010939,.007695,
.010759,.008368,
.010464,.009,
.010064,.009571,
.009571,.010064,
.009,.010464,
.008368,.010759,
.007695,.010939,
.007,.011,
-.007,.011,
-.007695,.010939,
-.008368,.010759,
-.009,.010464,
-.009571,.010064,
-.010064,.009571,
-.010464,.009,
-.010759,.008368,
-.010939,.007695,
-.011,.007,
-.011,-.007,
-.010939,-.007695,
-.010759,-.008368,
-.010464,-.009,
-.010064,-.009571,
-.009571,-.010064,
-.009,-.010464,
-.008368,-.010759,
-.007695,-.010939,
-.007,-.011,
.007,-.011,
.007695,-.010939,
.008368,-.010759,
.009,-.010464,
.009571,-.010064,
.010064,-.009571,
.010464,-.009,
.010759,-.008368,
.010939,-.007695,
.011,-.007,
0.0*
%
%ADD34MACRO34*%
%AMMACRO22*
4,1,40,.007,.011,
-.007,.011,
-.007695,.010939,
-.008368,.010759,
-.009,.010464,
-.009571,.010064,
-.010064,.009571,
-.010464,.009,
-.010759,.008368,
-.010939,.007695,
-.011,.007,
-.011,-.007,
-.010939,-.007695,
-.010759,-.008368,
-.010464,-.009,
-.010064,-.009571,
-.009571,-.010064,
-.009,-.010464,
-.008368,-.010759,
-.007695,-.010939,
-.007,-.011,
.007,-.011,
.007695,-.010939,
.008368,-.010759,
.009,-.010464,
.009571,-.010064,
.010064,-.009571,
.010464,-.009,
.010759,-.008368,
.010939,-.007695,
.011,-.007,
.011,.007,
.010939,.007695,
.010759,.008368,
.010464,.009,
.010064,.009571,
.009571,.010064,
.009,.010464,
.008368,.010759,
.007695,.010939,
.007,.011,
0.0*
%
%ADD22MACRO22*%
%ADD30R,.04X.022*%
%ADD27R,.032X.022*%
%ADD16R,.012X.033*%
%AMMACRO14*
21,1,.041,.02,0.0,0.0,39.*%
%ADD14MACRO14*%
%ADD24R,.048X.016*%
%ADD25R,.016X.048*%
%ADD29R,.063X.038*%
%ADD23R,.073X.049*%
%AMMACRO32*
4,1,40,-.008,-.012,
.008,-.012,
.008695,-.011939,
.009368,-.011759,
.01,-.011464,
.010571,-.011064,
.011064,-.010571,
.011464,-.01,
.011759,-.009368,
.011939,-.008695,
.012,-.008,
.012,.008,
.011939,.008695,
.011759,.009368,
.011464,.01,
.011064,.010571,
.010571,.011064,
.01,.011464,
.009368,.011759,
.008695,.011939,
.008,.012,
-.008,.012,
-.008695,.011939,
-.009368,.011759,
-.01,.011464,
-.010571,.011064,
-.011064,.010571,
-.011464,.01,
-.011759,.009368,
-.011939,.008695,
-.012,.008,
-.012,-.008,
-.011939,-.008695,
-.011759,-.009368,
-.011464,-.01,
-.011064,-.010571,
-.010571,-.011064,
-.01,-.011464,
-.009368,-.011759,
-.008695,-.011939,
-.008,-.012,
0.0*
%
%ADD32MACRO32*%
%AMMACRO18*
4,1,40,-.007,-.011,
.007,-.011,
.007695,-.010939,
.008368,-.010759,
.009,-.010464,
.009571,-.010064,
.010064,-.009571,
.010464,-.009,
.010759,-.008368,
.010939,-.007695,
.011,-.007,
.011,.007,
.010939,.007695,
.010759,.008368,
.010464,.009,
.010064,.009571,
.009571,.010064,
.009,.010464,
.008368,.010759,
.007695,.010939,
.007,.011,
-.007,.011,
-.007695,.010939,
-.008368,.010759,
-.009,.010464,
-.009571,.010064,
-.010064,.009571,
-.010464,.009,
-.010759,.008368,
-.010939,.007695,
-.011,.007,
-.011,-.007,
-.010939,-.007695,
-.010759,-.008368,
-.010464,-.009,
-.010064,-.009571,
-.009571,-.010064,
-.009,-.010464,
-.008368,-.010759,
-.007695,-.010939,
-.007,-.011,
0.0*
%
%ADD18MACRO18*%
%AMMACRO20*
4,1,40,-.011,.007,
-.011,-.007,
-.010939,-.007695,
-.010759,-.008368,
-.010464,-.009,
-.010064,-.009571,
-.009571,-.010064,
-.009,-.010464,
-.008368,-.010759,
-.007695,-.010939,
-.007,-.011,
.007,-.011,
.007695,-.010939,
.008368,-.010759,
.009,-.010464,
.009571,-.010064,
.010064,-.009571,
.010464,-.009,
.010759,-.008368,
.010939,-.007695,
.011,-.007,
.011,.007,
.010939,.007695,
.010759,.008368,
.010464,.009,
.010064,.009571,
.009571,.010064,
.009,.010464,
.008368,.010759,
.007695,.010939,
.007,.011,
-.007,.011,
-.007695,.010939,
-.008368,.010759,
-.009,.010464,
-.009571,.010064,
-.010064,.009571,
-.010464,.009,
-.010759,.008368,
-.010939,.007695,
-.011,.007,
0.0*
%
%ADD20MACRO20*%
%AMMACRO31*
4,1,40,-.008,-.012,
.008,-.012,
.008695,-.011939,
.009368,-.011759,
.01,-.011464,
.010571,-.011064,
.011064,-.010571,
.011464,-.01,
.011759,-.009368,
.011939,-.008695,
.012,-.008,
.012,.008,
.011939,.008695,
.011759,.009368,
.011464,.01,
.011064,.010571,
.010571,.011064,
.01,.011464,
.009368,.011759,
.008695,.011939,
.008,.012,
-.008,.012,
-.008695,.011939,
-.009368,.011759,
-.01,.011464,
-.010571,.011064,
-.011064,.010571,
-.011464,.01,
-.011759,.009368,
-.011939,.008695,
-.012,.008,
-.012,-.008,
-.011939,-.008695,
-.011759,-.009368,
-.011464,-.01,
-.011064,-.010571,
-.010571,-.011064,
-.01,-.011464,
-.009368,-.011759,
-.008695,-.011939,
-.008,-.012,
0.0*
%
%ADD31MACRO31*%
%AMMACRO19*
4,1,40,-.007,-.011,
.007,-.011,
.007695,-.010939,
.008368,-.010759,
.009,-.010464,
.009571,-.010064,
.010064,-.009571,
.010464,-.009,
.010759,-.008368,
.010939,-.007695,
.011,-.007,
.011,.007,
.010939,.007695,
.010759,.008368,
.010464,.009,
.010064,.009571,
.009571,.010064,
.009,.010464,
.008368,.010759,
.007695,.010939,
.007,.011,
-.007,.011,
-.007695,.010939,
-.008368,.010759,
-.009,.010464,
-.009571,.010064,
-.010064,.009571,
-.010464,.009,
-.010759,.008368,
-.010939,.007695,
-.011,.007,
-.011,-.007,
-.010939,-.007695,
-.010759,-.008368,
-.010464,-.009,
-.010064,-.009571,
-.009571,-.010064,
-.009,-.010464,
-.008368,-.010759,
-.007695,-.010939,
-.007,-.011,
0.0*
%
%ADD19MACRO19*%
%AMMACRO28*
4,1,40,-.011,.007,
-.011,-.007,
-.010939,-.007695,
-.010759,-.008368,
-.010464,-.009,
-.010064,-.009571,
-.009571,-.010064,
-.009,-.010464,
-.008368,-.010759,
-.007695,-.010939,
-.007,-.011,
.007,-.011,
.007695,-.010939,
.008368,-.010759,
.009,-.010464,
.009571,-.010064,
.010064,-.009571,
.010464,-.009,
.010759,-.008368,
.010939,-.007695,
.011,-.007,
.011,.007,
.010939,.007695,
.010759,.008368,
.010464,.009,
.010064,.009571,
.009571,.010064,
.009,.010464,
.008368,.010759,
.007695,.010939,
.007,.011,
-.007,.011,
-.007695,.010939,
-.008368,.010759,
-.009,.010464,
-.009571,.010064,
-.010064,.009571,
-.010464,.009,
-.010759,.008368,
-.010939,.007695,
-.011,.007,
0.0*
%
%ADD28MACRO28*%
%ADD35C,.012*%
%ADD36C,.022*%
%ADD37C,.016*%
%ADD38C,.004*%
%ADD39C,.006*%
%ADD40C,.007*%
%ADD41C,.008*%
%ADD47C,.05004*%
%ADD45C,.06404*%
%ADD46C,.09204*%
%ADD42C,.11004*%
%ADD44R,.008X.008*%
%ADD43C,.197*%
G75*
%LPD*%
G75*
G36*
G01X3937Y3001D02*
G02X3001Y3937I0J936D01*
G01Y12207D01*
G02X3755Y12392I400J0D01*
G03Y26978I13962J7293D01*
G02X3001Y27163I-354J185D01*
G01Y57874D01*
G02X3937Y58810I936J0D01*
G01X26500D01*
Y57000D01*
X25500Y56000D01*
Y54500D01*
X26900Y53100D01*
X27900D01*
X29026Y51974D01*
Y50526D01*
X28000Y49500D01*
X25900D01*
X24300Y47900D01*
Y46000D01*
X25900Y44400D01*
X28100D01*
X29026Y43474D01*
Y42026D01*
X28500Y41500D01*
X28190D01*
G03X28010I-90J-2200D01*
G01X26800D01*
X25800Y40500D01*
Y38400D01*
X27200Y37000D01*
X29000D01*
X30900Y35100D01*
X37000D01*
Y34000D01*
X38000Y33000D01*
X40000D01*
X40600Y33600D01*
X45400D01*
X46500Y32500D01*
Y29700D01*
X42300Y25500D01*
Y5300D01*
X40001Y3001D01*
X3937D01*
G37*
G36*
G01X37417Y19685D02*
G03I-19700J0D01*
G37*
G36*
G01X73500Y30000D02*
X72500Y31000D01*
Y35000D01*
X73500Y36000D01*
X74500D01*
X75000Y35500D01*
X77000D01*
X78500Y37000D01*
Y38500D01*
X79000Y39000D01*
X80500D01*
X80900Y38600D01*
Y38265D01*
G03X80898Y38200I1599J-82D01*
G01Y36800D01*
G03X80900Y36735I1601J17D01*
G01Y31400D01*
X79500Y30000D01*
X73500D01*
G37*
G36*
G01X49500Y19000D02*
X48600Y19900D01*
Y20235D01*
G03X48602Y20300I-1599J82D01*
G01Y21700D01*
G03X48600Y21765I-1601J-17D01*
G01Y29600D01*
X50000Y31000D01*
X54500D01*
X55400Y30100D01*
Y29765D01*
G03X55398Y29700I1599J-82D01*
G01Y28300D01*
G03X55400Y28235I1601J17D01*
G01Y27100D01*
X56400Y26100D01*
Y23600D01*
X57500Y22500D01*
X59800D01*
X60400Y21900D01*
Y21765D01*
G03X60398Y21700I1599J-82D01*
G01Y20300D01*
G03X60400Y20235I1601J17D01*
G01Y19900D01*
X59500Y19000D01*
X49500D01*
G37*
G36*
G01X92000D02*
X91100Y19900D01*
Y20235D01*
G03X91102Y20300I-1599J82D01*
G01Y21700D01*
G03X91100Y21765I-1601J-17D01*
G01Y29600D01*
X92500Y31000D01*
X102000D01*
X102437Y30563D01*
X102420Y30462D01*
G03X102398Y30200I1580J-265D01*
G01Y28800D01*
G03X102420Y28538I1602J3D01*
G01X102437Y28437D01*
X102000Y28000D01*
X97000D01*
X95500Y26500D01*
Y24500D01*
X97000Y23000D01*
X102000D01*
X102900Y22100D01*
Y21765D01*
G03X102898Y21700I1599J-82D01*
G01Y20300D01*
G03X102900Y20235I1601J17D01*
G01Y19900D01*
X102000Y19000D01*
X92000D01*
G37*
G36*
G01X118900Y18900D02*
X115600D01*
X114500Y20000D01*
Y25500D01*
X115500Y26500D01*
X119000D01*
X120000Y25500D01*
Y20000D01*
X118900Y18900D01*
G37*
G36*
G01X55561Y41100D02*
X54282Y42378D01*
Y43682D01*
X55100Y44500D01*
X58200D01*
X59700Y46000D01*
Y47900D01*
X58300Y49300D01*
X57315D01*
X55568D01*
X55200D01*
X54282Y50218D01*
Y51782D01*
X55700Y53200D01*
X64800D01*
X66000Y52000D01*
Y45100D01*
X65500Y44600D01*
X65365D01*
G03X65300Y44602I-82J-1599D01*
G01X63700D01*
G03X63635Y44600I17J-1601D01*
G01X62900D01*
X59400Y41100D01*
X55561D01*
G37*
G36*
G01X41690Y58810D02*
X42666Y57834D01*
X42622Y57714D01*
G03X42659Y56550I1456J-536D01*
G01X42676Y56511D01*
Y54376D01*
X42400Y54100D01*
X40700D01*
X39700Y53100D01*
X35400D01*
Y54580D01*
X35406Y54604D01*
G03Y56224I-3201J810D01*
G01X35400Y56248D01*
Y57900D01*
X36310Y58810D01*
X41690D01*
G37*
G36*
G01X138999Y3001D02*
X137000Y5000D01*
Y10000D01*
X136000Y11000D01*
Y20500D01*
X138500Y23000D01*
Y30000D01*
X128800Y39700D01*
X115300D01*
X112500Y42500D01*
X110000D01*
X101500Y51000D01*
Y53000D01*
X102500Y54000D01*
X106000D01*
X110300Y49700D01*
X112800D01*
X114500Y51400D01*
Y57000D01*
X116310Y58810D01*
X173228D01*
G02X174164Y57874I0J-936D01*
G01Y27165D01*
G02X173410Y26980I-400J0D01*
G03Y12390I-13961J-7295D01*
G02X174164Y12205I354J-185D01*
G01Y3937D01*
G02X173228Y3001I-936J0D01*
G01X138999D01*
G37*
G36*
G01X95000Y45500D02*
X88500D01*
X86500Y47500D01*
Y50000D01*
X87300Y50800D01*
X94500D01*
X96000Y49300D01*
Y46500D01*
X95000Y45500D01*
G37*
G36*
G01X81500Y47000D02*
X68500D01*
X67500Y48000D01*
Y52000D01*
X68500Y53000D01*
X81500D01*
X82500Y52000D01*
Y48000D01*
X81500Y47000D01*
G37*
G36*
G01X66400Y43400D02*
X68500Y45500D01*
X78000D01*
X79500Y44000D01*
Y41500D01*
X78000Y40000D01*
X75000D01*
X69500Y34500D01*
X57000D01*
X56000Y35500D01*
Y38600D01*
X57200Y39800D01*
X59800D01*
X63398Y43398D01*
X65998D01*
X65999Y43400D01*
X66400D01*
G37*
G36*
G01X179149Y19685D02*
G03I-19700J0D01*
G37*
G36*
G01X125500Y4500D02*
X124000Y6000D01*
Y14000D01*
X124900Y14900D01*
X125235D01*
G03X125300Y14898I82J1599D01*
G01X126700D01*
G03X126765Y14900I-17J1601D01*
G01X127400D01*
X128500Y16000D01*
Y19000D01*
X126500Y21000D01*
Y25500D01*
X127500Y26500D01*
X130000D01*
X130900Y27400D01*
X132735D01*
G03X132800Y27398I82J1599D01*
G01X134200D01*
G03X134265Y27400I-17J1601D01*
G01X134400D01*
X135000Y26800D01*
Y25500D01*
X134500Y25000D01*
X132500D01*
X131000Y23500D01*
Y14000D01*
X135500Y9500D01*
Y6000D01*
X134000Y4500D01*
X125500D01*
G37*
%LPC*%
G75*
G54D47*
X127500Y52264D03*
G54D45*
X127264Y43898D03*
G54D46*
X141000Y43000D03*
G54D42*
X9000Y48000D03*
X164500Y48500D03*
G54D44*
X50800Y19900D03*
X58200D03*
X50800Y22100D03*
X53200Y27900D03*
Y30100D03*
X93300Y19900D03*
X100700D03*
X93300Y22100D03*
X100700D03*
X63300Y47000D03*
Y41000D03*
X65700D03*
X124900Y12700D03*
X127100D03*
G54D43*
X17717Y19685D03*
X159449D03*
%LPD*%
G75*
G54D10*
X25827Y-9492D03*
X141000Y43000D03*
X519227Y-9492D03*
G54D20*
X83500Y29800D03*
X133500Y18800D03*
G54D11*
X17717Y19685D03*
X9000Y48000D03*
X26890Y46949D03*
X103642Y43898D03*
X56418Y46949D03*
X159449Y19685D03*
X164500Y48500D03*
X127264Y43898D03*
G54D30*
X89000Y49000D03*
X80000D03*
G54D21*
X101300Y25500D03*
X46300Y21000D03*
X88800D03*
X77300D03*
G54D12*
X28802Y13285D03*
X24117Y8600D03*
X11317D03*
X6632Y13285D03*
Y26085D03*
X11317Y30770D03*
X24117D03*
X28802Y26085D03*
X170534Y13285D03*
X165849Y8600D03*
X153049D03*
X148364Y13285D03*
Y26085D03*
X153049Y30770D03*
X165849D03*
X170534Y26085D03*
G54D40*
G01X28100Y39300D02*
X28800D01*
X30827Y41327D01*
Y43681D01*
G01X34200Y47000D02*
X32796Y45596D01*
Y43681D01*
G01X36733Y50217D02*
Y47067D01*
G01X42638Y43681D02*
Y46262D01*
X40670Y48230D01*
Y50217D01*
G01X111800Y52264D02*
X105603Y58461D01*
X45361D01*
X44078Y57178D01*
G01X44607Y50217D02*
Y46831D01*
G01X39400D02*
X38701Y46132D01*
Y43681D01*
G01X52218Y47067D02*
X52481Y47330D01*
Y50217D01*
G01X103700Y36400D02*
X99000Y41100D01*
Y46500D01*
G01X56000Y55500D02*
X92000D01*
X99000Y48500D01*
Y46500D01*
G01X47200Y47067D02*
X48544Y48411D01*
Y50217D01*
G01X49730Y46821D02*
X50512Y46039D01*
Y43681D01*
G54D31*
X64500Y42200D03*
G54D22*
X104700Y25500D03*
X49700Y21000D03*
X92200D03*
X80700D03*
G54D13*
X26811Y43012D03*
X56497Y50886D03*
G54D41*
G01X109000Y11000D02*
Y9000D01*
X113544Y4456D01*
X118110D01*
G01X95400Y12500D02*
Y8600D01*
X99544Y4456D01*
X103937D01*
G01X84100Y14900D02*
Y5900D01*
X85544Y4456D01*
X89764D01*
G01X81500Y12700D02*
Y6000D01*
X79956Y4456D01*
X75591D01*
G01X74200Y21700D02*
X70600D01*
X66000Y17100D01*
Y5000D01*
X65456Y4456D01*
X61417D01*
G01X53437Y13900D02*
Y6437D01*
X51456Y4456D01*
X47244D01*
G01X101250Y25500D02*
X98000D01*
G01X83500Y29750D02*
Y27902D01*
X84700Y26702D01*
G01X62250Y25000D02*
X64737D01*
X65300Y24437D01*
G01X104750Y29500D02*
Y31250D01*
X107500Y34000D01*
X112500D01*
X113500Y33000D01*
Y30250D01*
G01X104750Y25500D02*
Y29500D01*
G01X68750D02*
X68650Y29600D01*
X62500D01*
G01X57750Y29000D02*
X59500D01*
X60100Y29600D01*
X62500D01*
G01X58750Y25000D02*
Y26500D01*
X57750Y27500D01*
Y29000D01*
G01X110940Y23750D02*
X106250D01*
X105250Y22750D01*
Y21000D01*
G01D02*
Y19450D01*
X103937Y18137D01*
Y15230D01*
G01X88940Y28250D02*
Y24190D01*
X88750Y24000D01*
Y21000D01*
G01D02*
Y19250D01*
X89764Y18236D01*
Y15230D01*
G01X75250Y26940D02*
Y25250D01*
X77250Y23250D01*
Y21000D01*
G01D02*
X75591Y19341D01*
Y15230D01*
G01X65800Y21000D02*
X62750D01*
G01D02*
Y19450D01*
X61417Y18117D01*
Y15230D01*
G01X46000Y25600D02*
X46250Y25350D01*
Y21000D01*
G01D02*
Y19250D01*
X47244Y18256D01*
Y15230D01*
G01X83250Y37500D02*
Y39250D01*
X85400Y41400D01*
X89800D01*
X91500Y39700D01*
Y34750D01*
G01X83500Y33250D02*
Y35250D01*
X83250Y35500D01*
Y37500D01*
G01X133500Y18750D02*
Y15700D01*
G01Y29750D02*
Y31500D01*
X131000Y34000D01*
X126500D01*
X125500Y33000D01*
Y30250D01*
G01X133500Y22250D02*
X135250D01*
X136700Y23700D01*
Y28300D01*
X135250Y29750D01*
X133500D01*
G01X122940Y23750D02*
X122934Y23744D01*
Y20866D01*
X123800Y20000D01*
X125000D01*
X126000Y19000D01*
Y17250D01*
G01D02*
X124250D01*
X122230Y15230D01*
X118110D01*
G54D32*
X64500Y45800D03*
G54D23*
X118110Y4456D03*
Y15230D03*
X103937Y4456D03*
Y15230D03*
X89764Y4456D03*
Y15230D03*
X75591Y4456D03*
Y15230D03*
X61417Y4456D03*
Y15230D03*
X47244Y4456D03*
Y15230D03*
G54D14*
X26811Y50886D03*
X56497Y43012D03*
G54D24*
X68750Y29500D03*
Y26940D03*
X75250D03*
X68750Y32060D03*
X75250D03*
G54D33*
X126000Y17200D03*
X133500Y29700D03*
G54D15*
X32205Y38484D03*
Y55414D03*
X51103Y38484D03*
Y55414D03*
G54D25*
X88940Y28250D03*
X94060D03*
X116060Y30250D03*
X113500D03*
X110940D03*
Y23750D03*
X116060D03*
X94060Y34750D03*
X91500D03*
X88940D03*
X128060Y30250D03*
X125500D03*
X122940D03*
Y23750D03*
X128060D03*
G54D16*
X30827Y43681D03*
X32796D03*
Y50217D03*
X30827D03*
X34764Y43681D03*
X36733D03*
X38701D03*
X40670D03*
X42638D03*
X44607D03*
X46575D03*
X48544D03*
X50512D03*
X52481D03*
Y50217D03*
X50512D03*
X48544D03*
X46575D03*
X44607D03*
X42638D03*
X40670D03*
X38701D03*
X36733D03*
X34764D03*
G54D34*
X126000Y13800D03*
X133500Y26300D03*
G54D35*
G01X30827Y50217D02*
Y47067D01*
G01X34764Y50217D02*
Y52064D01*
X36930Y54230D01*
G01X38701Y50217D02*
Y53199D01*
G01X36930Y54230D02*
Y55414D01*
G01X58000Y38500D02*
X55613D01*
X52481Y41632D01*
Y43681D01*
G54D26*
X62500Y29600D03*
X46000Y25600D03*
X111800Y52264D03*
X96000Y55600D03*
X111700Y39600D03*
X99000Y46500D03*
X78000Y42500D03*
X127500Y52264D03*
Y37000D03*
G54D17*
G01X-149983Y-76117D02*
Y-156117D01*
G01D02*
X864117D01*
G01X-153983Y-60117D02*
G02I-12000J0D01*
G01X-159133D02*
G02I-6850J0D01*
G01X-165983Y-76117D02*
Y-44117D01*
G01X-149983Y-60117D02*
X-181983D01*
G01X-149983Y-76117D02*
X864117D01*
G01X-149983Y-111617D02*
X864117D01*
G01X25189Y57811D02*
X29808D01*
X32205Y55414D01*
G01X76617Y-76117D02*
Y-156117D01*
G01X80750Y21000D02*
X85000D01*
X85100Y21100D01*
G01X34700Y34100D02*
X36930Y36330D01*
Y38484D01*
G01X42500Y33300D02*
Y35654D01*
X41654Y36500D01*
Y38484D01*
G01X214117Y-76117D02*
Y-156117D01*
G01X329117Y-76117D02*
Y-156117D01*
G01X496617Y-76117D02*
Y-156117D01*
G01X666617Y-76117D02*
Y-156117D01*
G01X864117Y-76117D02*
Y-156117D01*
G01X892117Y-60117D02*
G02I-12000J0D01*
G01X886967D02*
G02I-6850J0D01*
G01X880117Y-76117D02*
Y-44117D01*
G01X896117Y-60117D02*
X864117D01*
X28100Y39300D03*
X34200Y47000D03*
X28100Y55300D03*
X20000Y55000D03*
X15000Y45000D03*
X5000Y38000D03*
Y55000D03*
X30827Y47067D03*
X68750Y24100D03*
X79940Y26850D03*
X70700Y11200D03*
X40100Y21692D03*
X35000Y5000D03*
X41200Y7400D03*
X98200Y16500D03*
X108140Y28132D03*
X109000Y11000D03*
X95400Y12500D03*
X84100Y14900D03*
X81500Y12700D03*
X74200Y21700D03*
X53437Y13900D03*
X71405Y19607D03*
X68500Y13800D03*
X98000Y25500D03*
X69000Y17200D03*
X84700Y26702D03*
X65300Y24437D03*
X65800Y21000D03*
X54500Y25500D03*
X98700Y21000D03*
X95300D03*
X85100Y21100D03*
X56200Y21000D03*
X52800D03*
X45250Y35850D03*
X36733Y47067D03*
X44607Y46831D03*
X39400D03*
X52218Y47067D03*
X56000Y55500D03*
X103700Y36400D03*
X39300Y35500D03*
X47200Y47067D03*
X49730Y46821D03*
X87900Y53100D03*
X103655Y52264D03*
X61300Y47250D03*
X88940Y39400D03*
X76000Y37750D03*
X87700Y43400D03*
X94800Y46800D03*
X93000Y49700D03*
X58000Y38500D03*
X74000Y34900D03*
X119400Y29800D03*
X143000Y5000D03*
X137000Y12750D03*
X133500Y15700D03*
X118300Y19900D03*
X134200Y9000D03*
X131000Y6000D03*
X119500Y33900D03*
X170000Y45000D03*
X135500D03*
X155000D03*
X165000Y55000D03*
X145000D03*
Y36500D03*
X119403Y52264D03*
G54D36*
G01X32205Y38484D02*
X36930D01*
G01X32205Y55414D02*
X36930D01*
G01X46378Y38484D02*
X51103D01*
G01X46378Y55414D02*
X51103D01*
G54D18*
X62200Y25000D03*
X105200Y21000D03*
X62700D03*
X104700Y29500D03*
X57700Y29000D03*
X83200Y37500D03*
G54D27*
X36930Y38484D03*
X41654D03*
X46378D03*
Y55414D03*
X41654D03*
X36930D03*
G54D37*
G01X68750Y24100D02*
Y26940D01*
G01X108140Y28132D02*
Y29140D01*
X109250Y30250D01*
X110940D01*
G01X88940Y34750D02*
Y39400D01*
G01X119400Y29800D02*
X119850Y30250D01*
X122940D01*
G54D28*
X83500Y33200D03*
X133500Y22200D03*
G54D19*
X58800Y25000D03*
X101800Y21000D03*
X59300D03*
X101300Y29500D03*
X54300Y29000D03*
X79800Y37500D03*
G54D38*
G01X28100Y55300D02*
X30800Y52600D01*
X32300D01*
X32796Y52104D01*
Y50217D01*
G01X45250Y35850D02*
X44000Y37100D01*
Y40000D01*
X45000Y41000D01*
X46000D01*
X46575Y41575D01*
Y43681D01*
G01X44078Y57178D02*
Y53578D01*
X43100Y52600D01*
X41200D01*
X40670Y52070D01*
Y50217D01*
G01X50512D02*
Y52012D01*
X51100Y52600D01*
X53100D01*
X56000Y55500D01*
G01X39300Y35500D02*
Y40000D01*
X38300Y41000D01*
X35500D01*
X34764Y41736D01*
Y43681D01*
G54D29*
X71000Y50200D03*
Y42800D03*
G54D39*
G01X-137600Y-128617D02*
Y-146117D01*
X-128866D01*
G01X-113987Y-136784D02*
X-113113Y-135909D01*
X-112458Y-134451D01*
X-112021Y-132408D01*
X-112458Y-130659D01*
X-113331Y-129492D01*
X-114860Y-128617D01*
X-120755D01*
Y-146117D01*
X-113550D01*
X-112021Y-144951D01*
X-111148Y-143200D01*
X-110711Y-141159D01*
X-111148Y-139117D01*
X-112458Y-137367D01*
X-113987Y-136784D01*
X-120755D01*
G01X-93430Y-130076D02*
X-94740Y-129200D01*
X-96268Y-128617D01*
X-98015D01*
X-99980Y-129492D01*
X-101508Y-130950D01*
X-102600Y-132701D01*
X-103473Y-135617D01*
X-103692Y-138242D01*
X-103255Y-140867D01*
X-102600Y-142617D01*
X-101290Y-144367D01*
X-99761Y-145534D01*
X-98233Y-146117D01*
X-96705D01*
X-95176Y-145534D01*
X-93866Y-144659D01*
X-92774Y-143493D01*
G01X-67600Y-128617D02*
Y-146117D01*
X-58866D01*
G01X-41366D02*
X-50100D01*
Y-128617D01*
X-41366D01*
G01X-44860Y-137075D02*
X-50100D01*
G01X-33036Y-146117D02*
Y-128617D01*
X-28670D01*
X-26923Y-129492D01*
X-25613Y-130659D01*
X-24521Y-132408D01*
X-23648Y-134451D01*
X-23430Y-137367D01*
X-23648Y-140284D01*
X-24521Y-142326D01*
X-25613Y-144076D01*
X-26923Y-145242D01*
X-28670Y-146117D01*
X-33036D01*
G01X10260Y-135909D02*
X8732Y-134742D01*
X7422Y-134451D01*
X5675Y-135034D01*
X4365Y-136200D01*
X3492Y-138242D01*
X3273Y-140284D01*
X3492Y-142326D01*
X4365Y-144076D01*
X5675Y-145534D01*
X7422Y-146117D01*
X8950Y-145534D01*
X10260Y-144367D01*
G01X28197Y-146117D02*
Y-134451D01*
G01Y-136492D02*
X27324Y-135326D01*
X26013Y-134742D01*
X24485Y-134451D01*
X22957Y-135034D01*
X21647Y-136200D01*
X20773Y-137950D01*
X20337Y-140284D01*
X20773Y-142617D01*
X21647Y-144367D01*
X22957Y-145534D01*
X24485Y-146117D01*
X26013Y-145825D01*
X27324Y-144951D01*
X28197Y-143784D01*
G01X38710Y-146117D02*
Y-134451D01*
G01Y-136784D02*
X39802Y-135617D01*
X40894Y-134742D01*
X42422Y-134451D01*
X43513Y-134742D01*
X44824Y-135617D01*
G01X63197Y-128617D02*
Y-146117D01*
G01Y-143493D02*
X62324Y-144951D01*
X61013Y-145825D01*
X59485Y-146117D01*
X57739Y-145534D01*
X56429Y-144076D01*
X55555Y-142326D01*
X55337Y-140284D01*
X55555Y-138242D01*
X56429Y-136492D01*
X57739Y-135034D01*
X59485Y-134451D01*
X61013Y-134742D01*
X62105Y-135326D01*
X63197Y-136492D01*
G01X-77660Y-101117D02*
Y-83617D01*
X-71983Y-98200D01*
X-66306Y-83617D01*
Y-101117D01*
G01X-54483D02*
X-55793Y-100825D01*
X-57103Y-99659D01*
X-57977Y-97617D01*
X-58413Y-95284D01*
X-57977Y-92950D01*
X-57103Y-90909D01*
X-55793Y-89742D01*
X-54483Y-89451D01*
X-53173Y-89742D01*
X-51863Y-90909D01*
X-50990Y-92950D01*
X-50771Y-95284D01*
X-50990Y-97617D01*
X-51863Y-99659D01*
X-53173Y-100825D01*
X-54483Y-101117D01*
G01X-33053Y-83617D02*
Y-101117D01*
G01Y-98493D02*
X-33926Y-99951D01*
X-35237Y-100825D01*
X-36765Y-101117D01*
X-38511Y-100534D01*
X-39821Y-99076D01*
X-40695Y-97326D01*
X-40913Y-95284D01*
X-40695Y-93242D01*
X-39821Y-91492D01*
X-38511Y-90034D01*
X-36765Y-89451D01*
X-35237Y-89742D01*
X-34145Y-90326D01*
X-33053Y-91492D01*
G01X-22758Y-93242D02*
X-15771D01*
X-16426Y-91200D01*
X-17518Y-90034D01*
X-19046Y-89451D01*
X-20575Y-89742D01*
X-21885Y-90617D01*
X-22758Y-92659D01*
X-23195Y-94409D01*
Y-96159D01*
X-22758Y-97909D01*
X-21666Y-99659D01*
X-20356Y-100825D01*
X-18828Y-101117D01*
X-17300Y-100534D01*
X-15771Y-98784D01*
G01X-1983Y-101117D02*
Y-83617D01*
G01X110317Y-146117D02*
Y-128617D01*
X107697Y-132117D01*
G01Y-146117D02*
X112937D01*
G01X123669Y-138826D02*
X125197Y-136784D01*
X126507Y-135617D01*
X128254Y-135034D01*
X129782Y-135617D01*
X130874Y-136784D01*
X131747Y-138534D01*
X131965Y-140575D01*
X131747Y-142326D01*
X130874Y-144076D01*
X129563Y-145534D01*
X128035Y-146117D01*
X126289Y-145534D01*
X124760Y-143784D01*
X123887Y-141159D01*
X123669Y-138242D01*
X124105Y-134451D01*
X124760Y-132408D01*
X125852Y-130367D01*
X127380Y-128909D01*
X128909Y-128617D01*
X130437Y-129200D01*
X131529Y-130659D01*
G01X140514Y-142617D02*
X141823Y-144659D01*
X143570Y-145825D01*
X145535Y-146117D01*
X147282Y-145825D01*
X149029Y-144367D01*
X150120Y-142617D01*
X150339Y-140867D01*
X149902Y-138826D01*
X148374Y-137367D01*
X146845Y-136784D01*
X144880D01*
G01X146845D02*
X148155Y-135909D01*
X149247Y-134451D01*
X149684Y-132701D01*
X149247Y-130950D01*
X148155Y-129492D01*
X146190Y-128617D01*
X144225Y-128909D01*
X142260Y-130076D01*
G01X158669Y-138826D02*
X160197Y-136784D01*
X161507Y-135617D01*
X163254Y-135034D01*
X164782Y-135617D01*
X165874Y-136784D01*
X166747Y-138534D01*
X166965Y-140575D01*
X166747Y-142326D01*
X165874Y-144076D01*
X164563Y-145534D01*
X163035Y-146117D01*
X161289Y-145534D01*
X159760Y-143784D01*
X158887Y-141159D01*
X158669Y-138242D01*
X159105Y-134451D01*
X159760Y-132408D01*
X160852Y-130367D01*
X162380Y-128909D01*
X163909Y-128617D01*
X165437Y-129200D01*
X166529Y-130659D01*
G01X180317Y-146117D02*
X181845Y-145825D01*
X183592Y-144951D01*
X184684Y-143493D01*
X185120Y-141450D01*
X184684Y-139409D01*
X183374Y-137659D01*
X181409Y-136784D01*
X179225D01*
X177915Y-136200D01*
X176823Y-134742D01*
X176387Y-132701D01*
X177042Y-130659D01*
X178570Y-129200D01*
X180317Y-128617D01*
X182063Y-129200D01*
X183592Y-130659D01*
X184247Y-132701D01*
X183810Y-134742D01*
X182719Y-136200D01*
X181409Y-136784D01*
X179225D01*
X177260Y-137659D01*
X175950Y-139409D01*
X175514Y-141450D01*
X175950Y-143493D01*
X177042Y-144951D01*
X178789Y-145825D01*
X180317Y-146117D01*
G01X97200Y-101117D02*
Y-83617D01*
X102440D01*
X104187Y-84492D01*
X105497Y-86534D01*
X105934Y-88867D01*
X105497Y-91200D01*
X104405Y-92950D01*
X102440Y-93826D01*
X97200D01*
G01X123870Y-85076D02*
X122560Y-84200D01*
X121032Y-83617D01*
X119285D01*
X117320Y-84492D01*
X115792Y-85950D01*
X114700Y-87701D01*
X113827Y-90617D01*
X113608Y-93242D01*
X114045Y-95867D01*
X114700Y-97617D01*
X116010Y-99367D01*
X117539Y-100534D01*
X119067Y-101117D01*
X120595D01*
X122124Y-100534D01*
X123434Y-99659D01*
X124526Y-98493D01*
G01X138313Y-91784D02*
X139187Y-90909D01*
X139842Y-89451D01*
X140279Y-87408D01*
X139842Y-85659D01*
X138969Y-84492D01*
X137440Y-83617D01*
X131545D01*
Y-101117D01*
X138750D01*
X140279Y-99951D01*
X141152Y-98200D01*
X141589Y-96159D01*
X141152Y-94117D01*
X139842Y-92367D01*
X138313Y-91784D01*
X131545D01*
G01X147517Y-106950D02*
X160617D01*
G01X166545Y-101117D02*
Y-83617D01*
X176589Y-101117D01*
Y-83617D01*
G01X189067Y-101117D02*
X187320Y-100825D01*
X185792Y-99659D01*
X184482Y-97909D01*
X183608Y-95867D01*
X183172Y-93534D01*
Y-91200D01*
X183608Y-88867D01*
X184482Y-86825D01*
X185792Y-85076D01*
X187320Y-83909D01*
X189067Y-83617D01*
X190813Y-83909D01*
X192342Y-85076D01*
X193652Y-86825D01*
X194526Y-88867D01*
X194962Y-91200D01*
Y-93534D01*
X194526Y-95867D01*
X193652Y-97909D01*
X192342Y-99659D01*
X190813Y-100825D01*
X189067Y-101117D01*
G01X258282Y-143784D02*
X260029Y-145242D01*
X261994Y-146117D01*
X263740D01*
X265487Y-145242D01*
X266797Y-143784D01*
X267452Y-141742D01*
X267015Y-139701D01*
X265924Y-137950D01*
X263959Y-136784D01*
X261339Y-136200D01*
X259810Y-135034D01*
X259155Y-132992D01*
X259592Y-130950D01*
X260684Y-129492D01*
X262212Y-128617D01*
X263740D01*
X265269Y-129200D01*
X266579Y-130659D01*
G01X282113Y-136784D02*
X282987Y-135909D01*
X283642Y-134451D01*
X284079Y-132408D01*
X283642Y-130659D01*
X282769Y-129492D01*
X281240Y-128617D01*
X275345D01*
Y-146117D01*
X282550D01*
X284079Y-144951D01*
X284952Y-143200D01*
X285389Y-141159D01*
X284952Y-139117D01*
X283642Y-137367D01*
X282113Y-136784D01*
X275345D01*
G01X239908Y-83617D02*
X245367Y-101117D01*
X250826Y-83617D01*
G01X267234Y-101117D02*
X258500D01*
Y-83617D01*
X267234D01*
G01X263740Y-92075D02*
X258500D01*
G01X276000Y-101117D02*
Y-83617D01*
X281459D01*
X283205Y-84492D01*
X284297Y-85659D01*
X284734Y-87992D01*
X284297Y-90326D01*
X282987Y-91784D01*
X281459Y-92659D01*
X276000D01*
G01X281459D02*
X284734Y-101117D01*
G01X297867Y-101700D02*
X297430Y-101409D01*
Y-100825D01*
X297867Y-100534D01*
X298304Y-100825D01*
Y-101409D01*
X297867Y-101700D01*
G01X399700Y-128617D02*
Y-146117D01*
X408434D01*
G01X421567D02*
Y-128617D01*
X418947Y-132117D01*
G01Y-146117D02*
X424187D01*
G01X373450Y-83617D02*
Y-101117D01*
X382184D01*
G01X399247D02*
Y-89451D01*
G01Y-91492D02*
X398374Y-90326D01*
X397063Y-89742D01*
X395535Y-89451D01*
X394007Y-90034D01*
X392697Y-91200D01*
X391823Y-92950D01*
X391387Y-95284D01*
X391823Y-97617D01*
X392697Y-99367D01*
X394007Y-100534D01*
X395535Y-101117D01*
X397063Y-100825D01*
X398374Y-99951D01*
X399247Y-98784D01*
G01X408232Y-106367D02*
X409542Y-106950D01*
X411289Y-106367D01*
X412380Y-105201D01*
X413254Y-103742D01*
X414563Y-99076D01*
X417402Y-89451D01*
G01X410415D02*
X414563Y-99076D01*
G01X427042Y-93242D02*
X434029D01*
X433374Y-91200D01*
X432282Y-90034D01*
X430754Y-89451D01*
X429225Y-89742D01*
X427915Y-90617D01*
X427042Y-92659D01*
X426605Y-94409D01*
Y-96159D01*
X427042Y-97909D01*
X428134Y-99659D01*
X429444Y-100825D01*
X430972Y-101117D01*
X432500Y-100534D01*
X434029Y-98784D01*
G01X444760Y-101117D02*
Y-89451D01*
G01Y-91784D02*
X445852Y-90617D01*
X446944Y-89742D01*
X448472Y-89451D01*
X449563Y-89742D01*
X450874Y-90617D01*
G01X515564Y-101117D02*
Y-83617D01*
X519930D01*
X521677Y-84492D01*
X522987Y-85659D01*
X524079Y-87408D01*
X524952Y-89451D01*
X525170Y-92367D01*
X524952Y-95284D01*
X524079Y-97326D01*
X522987Y-99076D01*
X521677Y-100242D01*
X519930Y-101117D01*
X515564D01*
G01X534592Y-93242D02*
X541579D01*
X540924Y-91200D01*
X539832Y-90034D01*
X538304Y-89451D01*
X536775Y-89742D01*
X535465Y-90617D01*
X534592Y-92659D01*
X534155Y-94409D01*
Y-96159D01*
X534592Y-97909D01*
X535684Y-99659D01*
X536994Y-100825D01*
X538522Y-101117D01*
X540050Y-100534D01*
X541579Y-98784D01*
G01X552092Y-99076D02*
X553184Y-100242D01*
X554712Y-101117D01*
X556022D01*
X557332Y-100534D01*
X558205Y-99659D01*
X558642Y-98493D01*
X558424Y-96742D01*
X557550Y-95867D01*
X553620Y-94117D01*
X552747Y-92075D01*
X553184Y-90617D01*
X554057Y-89742D01*
X555367Y-89451D01*
X556677Y-89742D01*
X557987Y-90617D01*
G01X572867Y-89451D02*
Y-101117D01*
G01Y-84784D02*
X572430Y-84492D01*
Y-83909D01*
X572867Y-83617D01*
X573304Y-83909D01*
Y-84492D01*
X572867Y-84784D01*
G01X587310Y-105492D02*
X588839Y-106659D01*
X590585Y-106950D01*
X592113Y-106659D01*
X593424Y-105201D01*
X594297Y-103159D01*
Y-89451D01*
G01Y-91784D02*
X593424Y-90617D01*
X592113Y-89742D01*
X590585Y-89451D01*
X588839Y-90034D01*
X587747Y-91200D01*
X586873Y-93242D01*
X586437Y-95284D01*
X586655Y-97034D01*
X587529Y-99076D01*
X588839Y-100534D01*
X590585Y-101117D01*
X591895Y-100825D01*
X593424Y-99659D01*
X594297Y-98493D01*
G01X604155Y-101117D02*
Y-89451D01*
G01Y-92367D02*
X605029Y-90909D01*
X606339Y-89742D01*
X608085Y-89451D01*
X609613Y-89742D01*
X610924Y-90909D01*
X611579Y-92950D01*
Y-101117D01*
G01X622092Y-93242D02*
X629079D01*
X628424Y-91200D01*
X627332Y-90034D01*
X625804Y-89451D01*
X624275Y-89742D01*
X622965Y-90617D01*
X622092Y-92659D01*
X621655Y-94409D01*
Y-96159D01*
X622092Y-97909D01*
X623184Y-99659D01*
X624494Y-100825D01*
X626022Y-101117D01*
X627550Y-100534D01*
X629079Y-98784D01*
G01X639810Y-101117D02*
Y-89451D01*
G01Y-91784D02*
X640902Y-90617D01*
X641994Y-89742D01*
X643522Y-89451D01*
X644613Y-89742D01*
X645924Y-90617D01*
G01X559969Y-128617D02*
X568265D01*
X559969Y-146117D01*
X568265D01*
G01X581617D02*
X579870Y-145825D01*
X578342Y-144659D01*
X577032Y-142909D01*
X576158Y-140867D01*
X575722Y-138534D01*
Y-136200D01*
X576158Y-133867D01*
X577032Y-131825D01*
X578342Y-130076D01*
X579870Y-128909D01*
X581617Y-128617D01*
X583363Y-128909D01*
X584892Y-130076D01*
X586202Y-131825D01*
X587076Y-133867D01*
X587512Y-136200D01*
Y-138534D01*
X587076Y-140867D01*
X586202Y-142909D01*
X584892Y-144659D01*
X583363Y-145825D01*
X581617Y-146117D01*
G01X603484D02*
X594750D01*
Y-128617D01*
X603484D01*
G01X599990Y-137075D02*
X594750D01*
G01X686567Y-128617D02*
X684820Y-129200D01*
X683510Y-130659D01*
X682637Y-132408D01*
X681982Y-134742D01*
X681764Y-137367D01*
X681982Y-139992D01*
X682637Y-142326D01*
X683510Y-144076D01*
X684820Y-145534D01*
X686567Y-146117D01*
X688313Y-145534D01*
X689624Y-144076D01*
X690497Y-142326D01*
X691152Y-139992D01*
X691370Y-137367D01*
X691152Y-134742D01*
X690497Y-132408D01*
X689624Y-130659D01*
X688313Y-129200D01*
X686567Y-128617D01*
G01X699919Y-131534D02*
X701229Y-129784D01*
X702757Y-128909D01*
X704504Y-128617D01*
X706687Y-129200D01*
X708215Y-130659D01*
X708652Y-132408D01*
X708434Y-134159D01*
X707560Y-135617D01*
X703194Y-138534D01*
X701229Y-140575D01*
X699919Y-143493D01*
X699482Y-146117D01*
X708652D01*
G01X717637Y-146700D02*
X725497Y-128617D01*
G01X739067D02*
X737320Y-129200D01*
X736010Y-130659D01*
X735137Y-132408D01*
X734482Y-134742D01*
X734264Y-137367D01*
X734482Y-139992D01*
X735137Y-142326D01*
X736010Y-144076D01*
X737320Y-145534D01*
X739067Y-146117D01*
X740813Y-145534D01*
X742124Y-144076D01*
X742997Y-142326D01*
X743652Y-139992D01*
X743870Y-137367D01*
X743652Y-134742D01*
X742997Y-132408D01*
X742124Y-130659D01*
X740813Y-129200D01*
X739067Y-128617D01*
G01X756130Y-146117D02*
X756567Y-142326D01*
X757222Y-139117D01*
X758095Y-136200D01*
X759187Y-132992D01*
X760934Y-128617D01*
X752200D01*
G01X770137Y-146700D02*
X777997Y-128617D01*
G01X787419Y-131534D02*
X788729Y-129784D01*
X790257Y-128909D01*
X792004Y-128617D01*
X794187Y-129200D01*
X795715Y-130659D01*
X796152Y-132408D01*
X795934Y-134159D01*
X795060Y-135617D01*
X790694Y-138534D01*
X788729Y-140575D01*
X787419Y-143493D01*
X786982Y-146117D01*
X796152D01*
G01X809067Y-128617D02*
X807320Y-129200D01*
X806010Y-130659D01*
X805137Y-132408D01*
X804482Y-134742D01*
X804264Y-137367D01*
X804482Y-139992D01*
X805137Y-142326D01*
X806010Y-144076D01*
X807320Y-145534D01*
X809067Y-146117D01*
X810813Y-145534D01*
X812124Y-144076D01*
X812997Y-142326D01*
X813652Y-139992D01*
X813870Y-137367D01*
X813652Y-134742D01*
X812997Y-132408D01*
X812124Y-130659D01*
X810813Y-129200D01*
X809067Y-128617D01*
G01X826567Y-146117D02*
Y-128617D01*
X823947Y-132117D01*
G01Y-146117D02*
X829187D01*
G01X843630D02*
X844067Y-142326D01*
X844722Y-139117D01*
X845595Y-136200D01*
X846687Y-132992D01*
X848434Y-128617D01*
X839700D01*
G01X734264Y-101117D02*
Y-83617D01*
X738630D01*
X740377Y-84492D01*
X741687Y-85659D01*
X742779Y-87408D01*
X743652Y-89451D01*
X743870Y-92367D01*
X743652Y-95284D01*
X742779Y-97326D01*
X741687Y-99076D01*
X740377Y-100242D01*
X738630Y-101117D01*
X734264D01*
G01X760497D02*
Y-89451D01*
G01Y-91492D02*
X759624Y-90326D01*
X758313Y-89742D01*
X756785Y-89451D01*
X755257Y-90034D01*
X753947Y-91200D01*
X753073Y-92950D01*
X752637Y-95284D01*
X753073Y-97617D01*
X753947Y-99367D01*
X755257Y-100534D01*
X756785Y-101117D01*
X758313Y-100825D01*
X759624Y-99951D01*
X760497Y-98784D01*
G01X774067Y-83617D02*
Y-101117D01*
G01X771010Y-89451D02*
X777124D01*
G01X788292Y-93242D02*
X795279D01*
X794624Y-91200D01*
X793532Y-90034D01*
X792004Y-89451D01*
X790475Y-89742D01*
X789165Y-90617D01*
X788292Y-92659D01*
X787855Y-94409D01*
Y-96159D01*
X788292Y-97909D01*
X789384Y-99659D01*
X790694Y-100825D01*
X792222Y-101117D01*
X793750Y-100534D01*
X795279Y-98784D01*
M02*
